# T6G (Grand Teton) — schematic netlist excerpt (pin names and nets, part order shuffled) for the footprints in the layout excerpt that follows; sources: Cadence DE-HDL packaged netlist, KiCad conversion of 04192023_DAF0TMB3IC0_F0TG_MB_C_brd_V02_OCP.brd

C2338  Q_CAP  22UF 4V 20% X6S  pkg C0402  page 73 : A = PVDDCR_CPU0_P1 ; B = GND
PR378  Q_RES  1K 1% CHIP  pkg 0402LF  page 222 : A = PVDDIO_P1 ; B = GND

(kicad_pcb
	(version 20260206)
	(generator "pcbnew")
	(generator_version "10.0")
	(general
		(thickness 1.6)
		(legacy_teardrops no)
	)
	(paper "A4")
	(title_block
		(title "04192023_DAF0TMB3IC0_F0TG_MB_C_brd_V02_OCP.brd")
		(comment 1 "Grand Teton / footprints 4950-4951 of 8354")
	)
	(layers
		(0 "F.Cu" signal "TOP")
		(4 "In1.Cu" signal "GND")
		(6 "In2.Cu" signal "IN1")
		(8 "In3.Cu" signal "GND1")
		(10 "In4.Cu" signal "IN2")
		(12 "In5.Cu" signal "GND2")
		(14 "In6.Cu" signal "IN3")
		(16 "In7.Cu" signal "GND3")
		(18 "In8.Cu" signal "VCC")
		(20 "In9.Cu" signal "VCC1")
		(22 "In10.Cu" signal "GND4")
		(24 "In11.Cu" signal "IN4")
		(26 "In12.Cu" signal "GND5")
		(28 "In13.Cu" signal "IN5")
		(30 "In14.Cu" signal "GND6")
		(32 "In15.Cu" signal "IN6")
		(34 "In16.Cu" signal "GND7")
		(2 "B.Cu" signal "BOTTOM")
		(9 "F.Adhes" user "F.Adhesive")
		(11 "B.Adhes" user "B.Adhesive")
		(13 "F.Paste" user "Package Geometry/Pastemask Top")
		(15 "B.Paste" user "Package Geometry/Pastemask Bottom")
		(5 "F.SilkS" user "Ref Des/Silkscreen Top")
		(7 "B.SilkS" user "Ref Des/Silkscreen Bottom")
		(1 "F.Mask" user "Board Geometry/Soldermask Top")
		(3 "B.Mask" user "Board Geometry/Soldermask Bottom")
		(17 "Dwgs.User" user "User.Drawings")
		(19 "Cmts.User" user "User.Comments")
		(21 "Eco1.User" user "User.Eco1")
		(23 "Eco2.User" user "User.Eco2")
		(25 "Edge.Cuts" user "Board Geometry/Outline")
		(27 "Margin" user)
		(31 "F.CrtYd" user "Package Geometry/Place Bound Top")
		(29 "B.CrtYd" user "Package Geometry/Place Bound Bottom")
		(35 "F.Fab" user "Ref Des/Assembly Top")
		(33 "B.Fab" user "Ref Des/Assembly Bottom")
	)
	(footprint ""
		(layer "B.Cu")
		(at 114.086386 -249.368564)
		(property "Reference" "C2338"
			(at 0 0 0)
			(layer "B.SilkS")
			(hide yes)
			(effects
				(font
					(size 1.27 1.27)
				)
				(justify mirror)
			)
		)
		(property "Value" ""
			(at 0 0 0)
			(layer "B.Fab")
			(effects
				(font
					(size 1.27 1.27)
				)
				(justify mirror)
			)
		)
		(duplicate_pad_numbers_are_jumpers no)
		(fp_line
			(start -0.7874 -0.4064)
			(end -0.7874 0.4064)
			(stroke
				(width 0.1524)
				(type default)
			)
			(layer "B.SilkS")
		)
		(fp_line
			(start -0.7874 0.4064)
			(end 0.7874 0.4064)
			(stroke
				(width 0.1524)
				(type default)
			)
			(layer "B.SilkS")
		)
		(fp_line
			(start 0.7874 -0.4064)
			(end -0.7874 -0.4064)
			(stroke
				(width 0.1524)
				(type default)
			)
			(layer "B.SilkS")
		)
		(fp_line
			(start 0.7874 0.4064)
			(end 0.7874 -0.4064)
			(stroke
				(width 0.1524)
				(type default)
			)
			(layer "B.SilkS")
		)
		(fp_line
			(start -0.67945 -0.3048)
			(end -0.67945 0.3048)
			(stroke
				(width 0.1)
				(type default)
			)
			(layer "B.Fab")
		)
		(fp_line
			(start -0.67945 0.3048)
			(end -0.120396 0.3048)
			(stroke
				(width 0.1)
				(type default)
			)
			(layer "B.Fab")
		)
		(fp_line
			(start -0.12065 -0.3048)
			(end -0.67945 -0.3048)
			(stroke
				(width 0.1)
				(type default)
			)
			(layer "B.Fab")
		)
		(fp_line
			(start -0.12065 -0.2794)
			(end -0.12065 -0.3048)
			(stroke
				(width 0.1)
				(type default)
			)
			(layer "B.Fab")
		)
		(fp_line
			(start -0.120396 0.2794)
			(end 0.12065 0.2794)
			(stroke
				(width 0.1)
				(type default)
			)
			(layer "B.Fab")
		)
		(fp_line
			(start -0.120396 0.3048)
			(end -0.120396 0.2794)
			(stroke
				(width 0.1)
				(type default)
			)
			(layer "B.Fab")
		)
		(fp_line
			(start 0.12065 -0.305054)
			(end 0.12065 -0.2794)
			(stroke
				(width 0.1)
				(type default)
			)
			(layer "B.Fab")
		)
		(fp_line
			(start 0.12065 -0.2794)
			(end -0.12065 -0.2794)
			(stroke
				(width 0.1)
				(type default)
			)
			(layer "B.Fab")
		)
		(fp_line
			(start 0.12065 0.2794)
			(end 0.12065 0.3048)
			(stroke
				(width 0.1)
				(type default)
			)
			(layer "B.Fab")
		)
		(fp_line
			(start 0.12065 0.3048)
			(end 0.67945 0.3048)
			(stroke
				(width 0.1)
				(type default)
			)
			(layer "B.Fab")
		)
		(fp_line
			(start 0.67945 -0.305054)
			(end 0.12065 -0.305054)
			(stroke
				(width 0.1)
				(type default)
			)
			(layer "B.Fab")
		)
		(fp_line
			(start 0.67945 0.3048)
			(end 0.67945 -0.305054)
			(stroke
				(width 0.1)
				(type default)
			)
			(layer "B.Fab")
		)
		(pad "1" smd circle
			(at 0.40005 0 180)
			(size 0 0)
			(layers "B.Cu" "B.Mask" "B.Paste")
			(net "PVDDCR_CPU0_P1")
		)
		(pad "2" smd circle
			(at -0.40005 0 180)
			(size 0 0)
			(layers "B.Cu" "B.Mask" "B.Paste")
			(net "GND")
		)
	)
	(footprint ""
		(layer "B.Cu")
		(at 23.577804 -338.08797 -90)
		(property "Reference" "PR378"
			(at 0 0 90)
			(layer "B.SilkS")
			(hide yes)
			(effects
				(font
					(size 1.27 1.27)
				)
				(justify mirror)
			)
		)
		(property "Value" ""
			(at 0 0 90)
			(layer "B.Fab")
			(effects
				(font
					(size 1.27 1.27)
				)
				(justify mirror)
			)
		)
		(duplicate_pad_numbers_are_jumpers no)
		(fp_line
			(start -0.7874 0.4064)
			(end 0.7874 0.4064)
			(stroke
				(width 0.1524)
				(type default)
			)
			(layer "B.SilkS")
		)
		(fp_line
			(start 0.7874 0.4064)
			(end 0.7874 -0.4064)
			(stroke
				(width 0.1524)
				(type default)
			)
			(layer "B.SilkS")
		)
		(fp_line
			(start -0.7874 -0.4064)
			(end -0.7874 0.4064)
			(stroke
				(width 0.1524)
				(type default)
			)
			(layer "B.SilkS")
		)
		(fp_line
			(start 0.7874 -0.4064)
			(end -0.7874 -0.4064)
			(stroke
				(width 0.1524)
				(type default)
			)
			(layer "B.SilkS")
		)
		(fp_line
			(start -0.67945 0.3048)
			(end -0.120396 0.3048)
			(stroke
				(width 0.1)
				(type default)
			)
			(layer "B.Fab")
		)
		(fp_line
			(start -0.120396 0.3048)
			(end -0.120396 0.2794)
			(stroke
				(width 0.1)
				(type default)
			)
			(layer "B.Fab")
		)
		(fp_line
			(start 0.12065 0.3048)
			(end 0.67945 0.3048)
			(stroke
				(width 0.1)
				(type default)
			)
			(layer "B.Fab")
		)
		(fp_line
			(start 0.67945 0.3048)
			(end 0.67945 -0.305054)
			(stroke
				(width 0.1)
				(type default)
			)
			(layer "B.Fab")
		)
		(fp_line
			(start -0.120396 0.2794)
			(end 0.12065 0.2794)
			(stroke
				(width 0.1)
				(type default)
			)
			(layer "B.Fab")
		)
		(fp_line
			(start 0.12065 0.2794)
			(end 0.12065 0.3048)
			(stroke
				(width 0.1)
				(type default)
			)
			(layer "B.Fab")
		)
		(fp_line
			(start -0.12065 -0.2794)
			(end -0.12065 -0.3048)
			(stroke
				(width 0.1)
				(type default)
			)
			(layer "B.Fab")
		)
		(fp_line
			(start 0.12065 -0.2794)
			(end -0.12065 -0.2794)
			(stroke
				(width 0.1)
				(type default)
			)
			(layer "B.Fab")
		)
		(fp_line
			(start -0.67945 -0.3048)
			(end -0.67945 0.3048)
			(stroke
				(width 0.1)
				(type default)
			)
			(layer "B.Fab")
		)
		(fp_line
			(start -0.12065 -0.3048)
			(end -0.67945 -0.3048)
			(stroke
				(width 0.1)
				(type default)
			)
			(layer "B.Fab")
		)
		(fp_line
			(start 0.12065 -0.305054)
			(end 0.12065 -0.2794)
			(stroke
				(width 0.1)
				(type default)
			)
			(layer "B.Fab")
		)
		(fp_line
			(start 0.67945 -0.305054)
			(end 0.12065 -0.305054)
			(stroke
				(width 0.1)
				(type default)
			)
			(layer "B.Fab")
		)
		(pad "1" smd circle
			(at 0.40005 0 90)
			(size 0 0)
			(layers "B.Cu" "B.Mask" "B.Paste")
			(net "PVDDIO_P1")
		)
		(pad "2" smd circle
			(at -0.40005 0 90)
			(size 0 0)
			(layers "B.Cu" "B.Mask" "B.Paste")
			(net "GND")
		)
	)
)
